(kicad_pcb
	(version 20260206)
	(generator "pcbnew")
	(generator_version "10.0")
	(general
		(thickness 1.6)
		(legacy_teardrops no)
	)
	(paper "A4")
	(title_block
		(title "Wiwynn_Tioga_Pass_MB.brd")
		(comment 1 "Tioga Pass / footprints 1078-1082 of 4770")
	)
	(layers
		(0 "F.Cu" signal "TOP")
		(4 "In1.Cu" signal "L2GND")
		(6 "In2.Cu" signal "L3")
		(8 "In3.Cu" signal "L4GND")
		(10 "In4.Cu" signal "L5")
		(12 "In5.Cu" signal "L6GND")
		(14 "In6.Cu" signal "L7VCC")
		(16 "In7.Cu" signal "L8VCC")
		(18 "In8.Cu" signal "L9GND")
		(20 "In9.Cu" signal "L10")
		(22 "In10.Cu" signal "L11GND")
		(24 "In11.Cu" signal "L12")
		(26 "In12.Cu" signal "L13GND")
		(2 "B.Cu" signal "BOTTOM")
		(9 "F.Adhes" user "F.Adhesive")
		(11 "B.Adhes" user "B.Adhesive")
		(13 "F.Paste" user "Package Geometry/Pastemask Top")
		(15 "B.Paste" user "Package Geometry/Pastemask Bottom")
		(5 "F.SilkS" user "Ref Des/Silkscreen Top")
		(7 "B.SilkS" user "Ref Des/Silkscreen Bottom")
		(1 "F.Mask" user "Board Geometry/Soldermask Top")
		(3 "B.Mask" user "Board Geometry/Soldermask Bottom")
		(17 "Dwgs.User" user "User.Drawings")
		(19 "Cmts.User" user "User.Comments")
		(21 "Eco1.User" user "User.Eco1")
		(23 "Eco2.User" user "User.Eco2")
		(25 "Edge.Cuts" user "Board Geometry/Outline")
		(27 "Margin" user)
		(31 "F.CrtYd" user "Package Geometry/Place Bound Top")
		(29 "B.CrtYd" user "Package Geometry/Place Bound Bottom")
		(35 "F.Fab" user "Ref Des/Assembly Top")
		(33 "B.Fab" user "Ref Des/Assembly Bottom")
	)
	(footprint ""
		(layer "F.Cu")
		(at 177.434494 -54.347618 -90)
		(property "Reference" "EU4E2"
			(at 3.320288 0.142494 0)
			(unlocked yes)
			(layer "F.SilkS")
			(effects
				(font
					(size 0.7874 0.5842)
					(thickness 0.1524)
				)
			)
		)
		(property "Value" ""
			(at 0 0 270)
			(layer "F.Fab")
			(effects
				(font
					(size 1.27 1.27)
				)
			)
		)
		(duplicate_pad_numbers_are_jumpers no)
		(fp_line
			(start -3.0099 3.429)
			(end -3.0099 -3.5052)
			(stroke
				(width 0.1524)
				(type default)
			)
			(layer "F.SilkS")
		)
		(fp_line
			(start 2.9718 3.429)
			(end -3.0099 3.429)
			(stroke
				(width 0.1524)
				(type default)
			)
			(layer "F.SilkS")
		)
		(fp_line
			(start -3.0099 -3.5052)
			(end 2.9718 -3.5052)
			(stroke
				(width 0.1524)
				(type default)
			)
			(layer "F.SilkS")
		)
		(fp_line
			(start 2.9718 -3.5052)
			(end 2.9718 3.429)
			(stroke
				(width 0.1524)
				(type default)
			)
			(layer "F.SilkS")
		)
		(fp_circle
			(center -3.057398 -2.678684)
			(end -3.057398 -2.805684)
			(stroke
				(width 0.254)
				(type default)
			)
			(fill no)
			(layer "F.SilkS")
		)
		(fp_poly
			(pts
				(xy -2.9972 -3.4925) (xy -2.9972 -2.6924) (xy -2.1971 -3.4925)
			)
			(stroke
				(width 0)
				(type default)
			)
			(fill yes)
			(layer "F.SilkS")
		)
		(fp_poly
			(pts
				(xy -2.549906 -3.050032) (xy -2.549906 3.050032) (xy 2.549906 3.050032) (xy 2.549906 -3.050032)
			)
			(stroke
				(width 0)
				(type default)
			)
			(fill no)
			(layer "F.CrtYd")
		)
		(fp_line
			(start -2.549906 3.050032)
			(end -2.549906 -3.050032)
			(stroke
				(width 0.1)
				(type default)
			)
			(layer "F.Fab")
		)
		(fp_line
			(start 2.549906 3.050032)
			(end -2.549906 3.050032)
			(stroke
				(width 0.1)
				(type default)
			)
			(layer "F.Fab")
		)
		(fp_line
			(start -2.549906 -3.050032)
			(end 2.549906 -3.050032)
			(stroke
				(width 0.1)
				(type default)
			)
			(layer "F.Fab")
		)
		(fp_line
			(start 2.549906 -3.050032)
			(end 2.549906 3.050032)
			(stroke
				(width 0.1)
				(type default)
			)
			(layer "F.Fab")
		)
		(fp_circle
			(center -3.057398 -2.678684)
			(end -3.057398 -2.805684)
			(stroke
				(width 0.254)
				(type default)
			)
			(fill no)
			(layer "F.Fab")
		)
		(pad "1" smd rect
			(at -2.39522 -2.279904 270)
			(size 0.7112 0.254)
			(layers "F.Cu" "F.Mask" "F.Paste")
			(net "PVCCIO_CPU1")
		)
		(pad "2" smd rect
			(at -2.39522 -1.83007 270)
			(size 0.7112 0.254)
			(layers "F.Cu" "F.Mask" "F.Paste")
			(net "GND")
		)
		(pad "3" smd rect
			(at -2.39522 -1.379982 270)
			(size 0.7112 0.254)
			(layers "F.Cu" "F.Mask" "F.Paste")
			(net "VR_PVCCIO_CPU1_PH1_VCIN")
		)
		(pad "4" smd rect
			(at -2.39522 -0.929894 270)
			(size 0.7112 0.254)
			(layers "F.Cu" "F.Mask" "F.Paste")
			(net "P5V_STBY")
		)
		(pad "5" smd rect
			(at -2.39522 -0.48006 270)
			(size 0.7112 0.254)
			(layers "F.Cu" "F.Mask" "F.Paste")
			(net "GND")
		)
		(pad "6" smd rect
			(at -2.39522 -0.029972 270)
			(size 0.7112 0.254)
			(layers "F.Cu" "F.Mask" "F.Paste")
			(net "TP_PVCCIO_CPU1_GL_0")
		)
		(pad "7" smd custom
			(at 0.016764 1.145032 270)
			(size 0.53975 0.53975)
			(layers "F.Cu" "F.Mask" "F.Paste")
			(net "GND")
			(options
				(clearance outline)
				(anchor circle)
			)
			(primitives
				(gr_poly
					(pts
						(xy -2.7051 1.0795) (xy -2.7051 -0.3683) (xy -0.9271 -0.3683) (xy -0.9271 -1.0795) (xy 2.7051 -1.0795)
						(xy 2.7051 1.0795)
					)
					(width 0)
					(fill yes)
				)
			)
		)
		(pad "10" smd rect
			(at -0.008382 2.874772 270)
			(size 4.3434 0.6096)
			(layers "F.Cu" "F.Mask" "F.Paste")
			(net "VR_PVCCIO_CPU1_PH1_SW")
		)
		(pad "25" smd rect
			(at 1.548384 -1.283208 270)
			(size 2.3368 2.0066)
			(layers "F.Cu" "F.Mask" "F.Paste")
			(net "VR_FET_SW_P12V_STBY_PVCCIN_CPU0")
		)
		(pad "30" smd rect
			(at 2.050034 -2.895092 270)
			(size 0.254 0.7112)
			(layers "F.Cu" "F.Mask" "F.Paste")
			(net "VR_FET_SW_P12V_STBY_PVCCIN_CPU0")
		)
		(pad "31" smd rect
			(at 1.599946 -2.895092 270)
			(size 0.254 0.7112)
			(layers "F.Cu" "F.Mask" "F.Paste")
			(net "Net_367")
		)
		(pad "32" smd rect
			(at 1.150112 -2.895092 270)
			(size 0.254 0.7112)
			(layers "F.Cu" "F.Mask" "F.Paste")
			(net "VR_PVCCIO_CPU1_PH1_PHASE")
		)
		(pad "33" smd rect
			(at 0.700024 -2.895092 270)
			(size 0.254 0.7112)
			(layers "F.Cu" "F.Mask" "F.Paste")
			(net "VR_PVCCIO_CPU1_PH1_BOOT_R")
		)
		(pad "34" smd rect
			(at 0.249936 -2.895092 270)
			(size 0.254 0.7112)
			(layers "F.Cu" "F.Mask" "F.Paste")
			(net "VR_PVCCIO_CPU1_PWM1")
		)
		(pad "35" smd rect
			(at -0.199898 -2.895092 270)
			(size 0.254 0.7112)
			(layers "F.Cu" "F.Mask" "F.Paste")
			(net "P5V_STBY")
		)
		(pad "36" smd rect
			(at -0.649986 -2.895092 270)
			(size 0.254 0.7112)
			(layers "F.Cu" "F.Mask" "F.Paste")
			(net "A_TSENSE_PVCCIO_CPU1")
		)
		(pad "37" smd rect
			(at -1.100074 -2.895092 270)
			(size 0.254 0.7112)
			(layers "F.Cu" "F.Mask" "F.Paste")
			(net "VR_PVCCIO_CPU1_OCSET")
		)
		(pad "38" smd rect
			(at -1.549908 -2.895092 270)
			(size 0.254 0.7112)
			(layers "F.Cu" "F.Mask" "F.Paste")
			(net "ISENSE_PVCCIO_CPU1_PH1_IMON")
		)
		(pad "39" smd rect
			(at -1.999996 -2.895092 270)
			(size 0.254 0.7112)
			(layers "F.Cu" "F.Mask" "F.Paste")
			(net "VR_PVCCIO_CPU1_AIREF1")
		)
		(pad "40" smd rect
			(at -0.871728 -1.283208 270)
			(size 1.8034 2.0066)
			(layers "F.Cu" "F.Mask" "F.Paste")
			(net "GND")
		)
		(pad "41" smd rect
			(at -1.533906 0.247904 270)
			(size 0.508 0.3556)
			(layers "F.Cu" "F.Mask" "F.Paste")
			(net "TP_PVCCIO_CPU1_GL_1")
		)
	)
	(footprint ""
		(layer "F.Cu")
		(at 29.6164 -59.617102 -90)
		(property "Reference" "C1E13"
			(at 0 0 270)
			(layer "F.SilkS")
			(hide yes)
			(effects
				(font
					(size 1.27 1.27)
				)
			)
		)
		(property "Value" ""
			(at 0 0 270)
			(layer "F.Fab")
			(effects
				(font
					(size 1.27 1.27)
				)
			)
		)
		(duplicate_pad_numbers_are_jumpers no)
		(fp_rect
			(start 0.3048 -0.1016)
			(end -0.3048 0.9906)
			(stroke
				(width 0)
				(type default)
			)
			(fill no)
			(layer "F.CrtYd")
		)
		(fp_line
			(start -0.3048 0.9906)
			(end 0.3048 0.9906)
			(stroke
				(width 0.1)
				(type default)
			)
			(layer "F.Fab")
		)
		(fp_line
			(start 0.3048 0.9906)
			(end 0.3048 -0.1016)
			(stroke
				(width 0.1)
				(type default)
			)
			(layer "F.Fab")
		)
		(fp_line
			(start -0.3048 -0.1016)
			(end -0.3048 0.9906)
			(stroke
				(width 0.1)
				(type default)
			)
			(layer "F.Fab")
		)
		(fp_line
			(start 0.3048 -0.1016)
			(end -0.3048 -0.1016)
			(stroke
				(width 0.1)
				(type default)
			)
			(layer "F.Fab")
		)
		(pad "1" smd rect
			(at 0 0 270)
			(size 0.508 0.508)
			(layers "F.Cu" "F.Mask" "F.Paste")
			(net "VR_FET_SW_P12V_STBY_PVCCIN_CPU1")
		)
		(pad "2" smd rect
			(at 0 0.889 270)
			(size 0.508 0.508)
			(layers "F.Cu" "F.Mask" "F.Paste")
			(net "GND")
		)
		(zone
			(layer "F.Cu")
			(hatch none 0.5)
			(connect_pads
				(clearance 0)
			)
			(min_thickness 0.25)
			(keepout
				(tracks not_allowed)
				(vias allowed)
				(pads allowed)
				(copperpour not_allowed)
				(footprints allowed)
			)
			(placement
				(enabled no)
				(sheetname "")
			)
			(fill
				(thermal_gap 0.5)
				(thermal_bridge_width 0.5)
				(island_removal_mode 0)
			)
			(polygon
				(pts
					(xy 29.3624 -59.363102) (xy 29.3624 -59.871102) (xy 28.9814 -59.871102) (xy 28.9814 -59.363102)
				)
			)
		)
		(zone
			(layer "F.Cu")
			(hatch none 0.5)
			(connect_pads
				(clearance 0)
			)
			(min_thickness 0.25)
			(keepout
				(tracks allowed)
				(vias not_allowed)
				(pads allowed)
				(copperpour not_allowed)
				(footprints allowed)
			)
			(placement
				(enabled no)
				(sheetname "")
			)
			(fill
				(thermal_gap 0.5)
				(thermal_bridge_width 0.5)
				(island_removal_mode 0)
			)
			(polygon
				(pts
					(xy 29.3624 -59.363102) (xy 29.3624 -59.871102) (xy 28.9814 -59.871102) (xy 28.9814 -59.363102)
				)
			)
		)
	)
	(footprint ""
		(layer "F.Cu")
		(at 341.3506 -147.461224 180)
		(property "Reference" "L7A3"
			(at 3.378708 -4.251706 180)
			(unlocked yes)
			(layer "F.SilkS")
			(effects
				(font
					(size 0.4064 0.254)
					(thickness 0.1524)
				)
			)
		)
		(property "Value" ""
			(at 0 0 180)
			(layer "F.Fab")
			(effects
				(font
					(size 1.27 1.27)
				)
			)
		)
		(duplicate_pad_numbers_are_jumpers no)
		(fp_line
			(start 8.3693 3.199892)
			(end -1.1303 3.199892)
			(stroke
				(width 0.1524)
				(type default)
			)
			(layer "F.SilkS")
		)
		(fp_line
			(start 8.3693 1.6637)
			(end 8.3693 3.199892)
			(stroke
				(width 0.1524)
				(type default)
			)
			(layer "F.SilkS")
		)
		(fp_line
			(start 8.3693 -3.199892)
			(end 8.3693 -1.6637)
			(stroke
				(width 0.1524)
				(type default)
			)
			(layer "F.SilkS")
		)
		(fp_line
			(start -1.1303 3.199892)
			(end -1.1303 1.6637)
			(stroke
				(width 0.1524)
				(type default)
			)
			(layer "F.SilkS")
		)
		(fp_line
			(start -1.1303 -1.6637)
			(end -1.1303 -3.199892)
			(stroke
				(width 0.1524)
				(type default)
			)
			(layer "F.SilkS")
		)
		(fp_line
			(start -1.1303 -3.199892)
			(end 8.3693 -3.199892)
			(stroke
				(width 0.1524)
				(type default)
			)
			(layer "F.SilkS")
		)
		(fp_rect
			(start -1.1303 3.199892)
			(end 8.3693 -3.199892)
			(stroke
				(width 0)
				(type default)
			)
			(fill no)
			(layer "F.CrtYd")
		)
		(fp_line
			(start 8.3693 3.199892)
			(end -1.1303 3.199892)
			(stroke
				(width 0.1)
				(type default)
			)
			(layer "F.Fab")
		)
		(fp_line
			(start 8.3693 -3.199892)
			(end 8.3693 3.199892)
			(stroke
				(width 0.1)
				(type default)
			)
			(layer "F.Fab")
		)
		(fp_line
			(start -1.1303 3.199892)
			(end -1.1303 -3.199892)
			(stroke
				(width 0.1)
				(type default)
			)
			(layer "F.Fab")
		)
		(fp_line
			(start -1.1303 -3.199892)
			(end 8.3693 -3.199892)
			(stroke
				(width 0.1)
				(type default)
			)
			(layer "F.Fab")
		)
		(pad "1" smd rect
			(at 0 0 180)
			(size 3.683 2.667)
			(layers "F.Cu" "F.Mask" "F.Paste")
			(net "VR_PVDDQ_DEF_PH2_SW")
		)
		(pad "2" smd rect
			(at 7.239 0 180)
			(size 3.683 2.667)
			(layers "F.Cu" "F.Mask" "F.Paste")
			(net "PVDDQ_DEF")
		)
	)
	(footprint ""
		(layer "F.Cu")
		(at 292.248082 12.01039 -90)
		(property "Reference" "T1P17"
			(at 0 0 270)
			(layer "F.SilkS")
			(hide yes)
			(effects
				(font
					(size 1.27 1.27)
				)
			)
		)
		(property "Value" "*"
			(at -3.302 1.12395 270)
			(unlocked yes)
			(layer "F.Fab")
			(hide yes)
			(effects
				(font
					(size 0.889 0.889)
					(thickness 0.1524)
				)
			)
		)
		(property "Device Type" "TPAD-DIFF-4P-GP_DISCRET-GB3-TPA"
			(at -3.302 -0.40005 270)
			(unlocked yes)
			(layer "F.Fab")
			(hide yes)
			(effects
				(font
					(size 0.889 0.889)
					(thickness 0.1524)
				)
			)
		)
		(duplicate_pad_numbers_are_jumpers no)
		(fp_line
			(start -2.286 2.286)
			(end 2.286 2.286)
			(stroke
				(width 0.1524)
				(type default)
			)
			(layer "F.SilkS")
		)
		(fp_line
			(start 2.286 2.286)
			(end 2.286 -2.286)
			(stroke
				(width 0.1524)
				(type default)
			)
			(layer "F.SilkS")
		)
		(fp_line
			(start -2.286 -2.286)
			(end -2.286 2.286)
			(stroke
				(width 0.1524)
				(type default)
			)
			(layer "F.SilkS")
		)
		(fp_line
			(start 2.286 -2.286)
			(end -2.286 -2.286)
			(stroke
				(width 0.1524)
				(type default)
			)
			(layer "F.SilkS")
		)
		(fp_line
			(start -2.413 -2.413)
			(end -2.413 -1.143)
			(stroke
				(width 0.4064)
				(type default)
			)
			(layer "F.SilkS")
		)
		(fp_line
			(start -1.143 -2.413)
			(end -2.413 -2.413)
			(stroke
				(width 0.4064)
				(type default)
			)
			(layer "F.SilkS")
		)
		(fp_rect
			(start -2.54 2.54)
			(end 2.54 -2.54)
			(stroke
				(width 0)
				(type default)
			)
			(fill no)
			(layer "F.CrtYd")
		)
		(fp_rect
			(start -2.54 2.54)
			(end 2.54 -2.54)
			(stroke
				(width 0)
				(type default)
			)
			(fill no)
			(layer "F.Fab")
		)
		(pad "1" thru_hole circle
			(at -1.27 -1.27 270)
			(size 1.524 1.524)
			(drill 0.9144)
			(layers "*.Cu" "*.Mask")
			(remove_unused_layers no)
			(net "L12_95OHM_6INCH_DP")
			(clearance -0.0508)
			(thermal_gap 0.127)
			(padstack
				(mode front_inner_back)
				(layer "Inner"
					(shape circle)
					(size 1.1684 1.1684)
					(clearance 0.127)
				)
				(layer "B.Cu"
					(shape circle)
					(size 1.524 1.524)
					(clearance -0.0508)
				)
			)
		)
		(pad "2" thru_hole circle
			(at 1.27 -1.27 270)
			(size 1.524 1.524)
			(drill 0.9144)
			(layers "*.Cu" "*.Mask")
			(remove_unused_layers no)
			(net "L12_95OHM_6INCH_DN")
			(clearance -0.0508)
			(thermal_gap 0.127)
			(padstack
				(mode front_inner_back)
				(layer "Inner"
					(shape circle)
					(size 1.1684 1.1684)
					(clearance 0.127)
				)
				(layer "B.Cu"
					(shape circle)
					(size 1.524 1.524)
					(clearance -0.0508)
				)
			)
		)
		(pad "GND1" thru_hole rect
			(at -1.27 1.27 270)
			(size 1.524 1.524)
			(drill 0.9144)
			(layers "*.Cu" "*.Mask")
			(remove_unused_layers no)
			(net "GND")
			(clearance -0.0508)
			(thermal_gap 0.127)
			(padstack
				(mode front_inner_back)
				(layer "Inner"
					(shape circle)
					(size 1.1684 1.1684)
					(clearance 0.127)
				)
				(layer "B.Cu"
					(shape rect)
					(size 1.524 1.524)
					(clearance -0.0508)
				)
			)
		)
		(pad "GND2" thru_hole rect
			(at 1.27 1.27 270)
			(size 1.524 1.524)
			(drill 0.9144)
			(layers "*.Cu" "*.Mask")
			(remove_unused_layers no)
			(net "GND")
			(clearance -0.0508)
			(thermal_gap 0.127)
			(padstack
				(mode front_inner_back)
				(layer "Inner"
					(shape circle)
					(size 1.1684 1.1684)
					(clearance 0.127)
				)
				(layer "B.Cu"
					(shape rect)
					(size 1.524 1.524)
					(clearance -0.0508)
				)
			)
		)
	)
	(footprint ""
		(layer "F.Cu")
		(at 451.85838 -34.7345 90)
		(property "Reference" "R25W35"
			(at 0 0 90)
			(layer "F.SilkS")
			(hide yes)
			(effects
				(font
					(size 1.27 1.27)
				)
			)
		)
		(property "Value" "*"
			(at 0.064008 -4.108196 90)
			(unlocked yes)
			(layer "F.Fab")
			(hide yes)
			(effects
				(font
					(size 1.27 1.016)
					(thickness 0.1524)
				)
			)
		)
		(property "Device Type" "120R2F-GP_RCL_GP-120R2F-GP,64.A"
			(at 0.064008 -5.632196 90)
			(unlocked yes)
			(layer "F.Fab")
			(hide yes)
			(effects
				(font
					(size 1.27 1.016)
					(thickness 0.1524)
				)
			)
		)
		(duplicate_pad_numbers_are_jumpers no)
		(fp_line
			(start 0.508 -0.9398)
			(end -0.508 -0.9398)
			(stroke
				(width 0.1524)
				(type default)
			)
			(layer "F.SilkS")
		)
		(fp_line
			(start -0.508 -0.9398)
			(end -0.508 0.9398)
			(stroke
				(width 0.1524)
				(type default)
			)
			(layer "F.SilkS")
		)
		(fp_rect
			(start -0.508 0.9398)
			(end 0.508 -0.9398)
			(stroke
				(width 0)
				(type default)
			)
			(fill no)
			(layer "F.CrtYd")
		)
		(fp_rect
			(start -0.508 0.9398)
			(end 0.508 -0.9398)
			(stroke
				(width 0)
				(type default)
			)
			(fill no)
			(layer "F.Fab")
		)
		(pad "1" smd custom
			(at 0 -0.4445 90)
			(size 0.1397 0.1397)
			(layers "F.Cu" "F.Mask" "F.Paste")
			(net "BMC_M_BA0")
			(options
				(clearance outline)
				(anchor circle)
			)
			(primitives
				(gr_poly
					(pts
						(arc
							(start -0.1778 -0.2794)
							(mid -0.249642 -0.249642)
							(end -0.2794 -0.1778)
						)
						(arc
							(start -0.2794 0.1778)
							(mid -0.249642 0.249642)
							(end -0.1778 0.2794)
						)
						(arc
							(start 0.1778 0.2794)
							(mid 0.249642 0.249642)
							(end 0.2794 0.1778)
						)
						(arc
							(start 0.2794 -0.1778)
							(mid 0.249642 -0.249642)
							(end 0.1778 -0.2794)
						)
					)
					(width 0)
					(fill yes)
				)
			)
		)
		(pad "2" smd custom
			(at 0 0.4445 90)
			(size 0.1397 0.1397)
			(layers "F.Cu" "F.Mask" "F.Paste")
			(net "P1V2_AUX_BMC")
			(options
				(clearance outline)
				(anchor circle)
			)
			(primitives
				(gr_poly
					(pts
						(arc
							(start -0.1778 -0.2794)
							(mid -0.249642 -0.249642)
							(end -0.2794 -0.1778)
						)
						(arc
							(start -0.2794 0.1778)
							(mid -0.249642 0.249642)
							(end -0.1778 0.2794)
						)
						(arc
							(start 0.1778 0.2794)
							(mid 0.249642 0.249642)
							(end 0.2794 0.1778)
						)
						(arc
							(start 0.2794 -0.1778)
							(mid 0.249642 -0.249642)
							(end 0.1778 -0.2794)
						)
					)
					(width 0)
					(fill yes)
				)
			)
		)
	)
)
